(kicad_pcb
	(version 20260206)
	(generator "pcbnew")
	(generator_version "10.0")
	(general
		(thickness 1.6)
		(legacy_teardrops no)
	)
	(paper "A4")
	(title_block
		(title "01162023_DA0F0TEBIF0_F0T_Expander_BD_F_brd_V02_OCP.brd")
		(comment 1 "Grand Teton / footprints 4581-4582 of 9728")
	)
	(layers
		(0 "F.Cu" signal "TOP")
		(4 "In1.Cu" signal "GND")
		(6 "In2.Cu" signal "VCC")
		(8 "In3.Cu" signal "VCC1")
		(10 "In4.Cu" signal "GND1")
		(12 "In5.Cu" signal "IN1")
		(14 "In6.Cu" signal "GND2")
		(16 "In7.Cu" signal "IN2")
		(18 "In8.Cu" signal "GND3")
		(20 "In9.Cu" signal "IN3")
		(22 "In10.Cu" signal "GND4")
		(24 "In11.Cu" signal "IN4")
		(26 "In12.Cu" signal "GND5")
		(28 "In13.Cu" signal "IN5")
		(30 "In14.Cu" signal "GND6")
		(32 "In15.Cu" signal "IN6")
		(34 "In16.Cu" signal "GND7")
		(2 "B.Cu" signal "BOTTOM")
		(9 "F.Adhes" user "F.Adhesive")
		(11 "B.Adhes" user "B.Adhesive")
		(13 "F.Paste" user "Package Geometry/Pastemask Top")
		(15 "B.Paste" user "Package Geometry/Pastemask Bottom")
		(5 "F.SilkS" user "Ref Des/Silkscreen Top")
		(7 "B.SilkS" user "Ref Des/Silkscreen Bottom")
		(1 "F.Mask" user "Board Geometry/Soldermask Top")
		(3 "B.Mask" user "Board Geometry/Soldermask Bottom")
		(17 "Dwgs.User" user "User.Drawings")
		(19 "Cmts.User" user "User.Comments")
		(21 "Eco1.User" user "User.Eco1")
		(23 "Eco2.User" user "User.Eco2")
		(25 "Edge.Cuts" user "Board Geometry/Outline")
		(27 "Margin" user)
		(31 "F.CrtYd" user "Package Geometry/Place Bound Top")
		(29 "B.CrtYd" user "Package Geometry/Place Bound Bottom")
		(35 "F.Fab" user "Ref Des/Assembly Top")
		(33 "B.Fab" user "Ref Des/Assembly Bottom")
	)
	(footprint ""
		(layer "F.Cu")
		(at 248.63171 -162.003994 -90)
		(property "Reference" "R952"
			(at 0 0 270)
			(layer "F.SilkS")
			(hide yes)
			(effects
				(font
					(size 1.27 1.27)
				)
			)
		)
		(property "Value" ""
			(at 0 0 270)
			(layer "F.Fab")
			(effects
				(font
					(size 1.27 1.27)
				)
			)
		)
		(duplicate_pad_numbers_are_jumpers no)
		(fp_line
			(start -0.7874 0.4064)
			(end -0.7874 -0.4064)
			(stroke
				(width 0.1524)
				(type default)
			)
			(layer "F.SilkS")
		)
		(fp_line
			(start 0.7874 0.4064)
			(end -0.7874 0.4064)
			(stroke
				(width 0.1524)
				(type default)
			)
			(layer "F.SilkS")
		)
		(fp_line
			(start -0.7874 -0.4064)
			(end 0.7874 -0.4064)
			(stroke
				(width 0.1524)
				(type default)
			)
			(layer "F.SilkS")
		)
		(fp_line
			(start 0.7874 -0.4064)
			(end 0.7874 0.4064)
			(stroke
				(width 0.1524)
				(type default)
			)
			(layer "F.SilkS")
		)
		(fp_line
			(start -0.67945 0.3048)
			(end -0.67945 -0.305054)
			(stroke
				(width 0.1)
				(type default)
			)
			(layer "F.Fab")
		)
		(fp_line
			(start -0.12065 0.3048)
			(end -0.67945 0.3048)
			(stroke
				(width 0.1)
				(type default)
			)
			(layer "F.Fab")
		)
		(fp_line
			(start 0.120396 0.3048)
			(end 0.120396 0.2794)
			(stroke
				(width 0.1)
				(type default)
			)
			(layer "F.Fab")
		)
		(fp_line
			(start 0.67945 0.3048)
			(end 0.120396 0.3048)
			(stroke
				(width 0.1)
				(type default)
			)
			(layer "F.Fab")
		)
		(fp_line
			(start -0.12065 0.2794)
			(end -0.12065 0.3048)
			(stroke
				(width 0.1)
				(type default)
			)
			(layer "F.Fab")
		)
		(fp_line
			(start 0.120396 0.2794)
			(end -0.12065 0.2794)
			(stroke
				(width 0.1)
				(type default)
			)
			(layer "F.Fab")
		)
		(fp_line
			(start -0.12065 -0.2794)
			(end 0.12065 -0.2794)
			(stroke
				(width 0.1)
				(type default)
			)
			(layer "F.Fab")
		)
		(fp_line
			(start 0.12065 -0.2794)
			(end 0.12065 -0.3048)
			(stroke
				(width 0.1)
				(type default)
			)
			(layer "F.Fab")
		)
		(fp_line
			(start 0.12065 -0.3048)
			(end 0.67945 -0.3048)
			(stroke
				(width 0.1)
				(type default)
			)
			(layer "F.Fab")
		)
		(fp_line
			(start 0.67945 -0.3048)
			(end 0.67945 0.3048)
			(stroke
				(width 0.1)
				(type default)
			)
			(layer "F.Fab")
		)
		(fp_line
			(start -0.67945 -0.305054)
			(end -0.12065 -0.305054)
			(stroke
				(width 0.1)
				(type default)
			)
			(layer "F.Fab")
		)
		(fp_line
			(start -0.12065 -0.305054)
			(end -0.12065 -0.2794)
			(stroke
				(width 0.1)
				(type default)
			)
			(layer "F.Fab")
		)
		(pad "1" smd circle
			(at -0.40005 0 270)
			(size 0 0)
			(layers "F.Cu" "F.Mask" "F.Paste")
			(net "HP_NIC4_EN")
		)
		(pad "2" smd circle
			(at 0.40005 0 270)
			(size 0 0)
			(layers "F.Cu" "F.Mask" "F.Paste")
			(net "P12V_NIC4_CO_EN")
		)
	)
	(footprint ""
		(layer "F.Cu")
		(at 132.721096 -177.650394)
		(property "Reference" "U114"
			(at -4.385818 -3.764534 0)
			(unlocked yes)
			(layer "F.SilkS")
			(effects
				(font
					(size 0.7874 0.5842)
					(thickness 0.1524)
				)
				(justify left)
			)
		)
		(property "Value" ""
			(at 0 0 0)
			(layer "F.Fab")
			(effects
				(font
					(size 1.27 1.27)
				)
			)
		)
		(duplicate_pad_numbers_are_jumpers no)
		(fp_poly
			(pts
				(xy -4.191 -3.258058) (xy -4.191 -2.242058) (xy -3.175 -2.750058)
			)
			(stroke
				(width 0)
				(type default)
			)
			(fill yes)
			(layer "F.SilkS")
		)
		(fp_line
			(start -3.050032 -3.050032)
			(end -3.050032 3.050032)
			(stroke
				(width 0.1)
				(type default)
			)
			(layer "F.Fab")
		)
		(fp_line
			(start -3.050032 3.050032)
			(end 3.050032 3.050032)
			(stroke
				(width 0.1)
				(type default)
			)
			(layer "F.Fab")
		)
		(fp_line
			(start 3.050032 -3.050032)
			(end -3.050032 -3.050032)
			(stroke
				(width 0.1)
				(type default)
			)
			(layer "F.Fab")
		)
		(fp_line
			(start 3.050032 3.050032)
			(end 3.050032 -3.050032)
			(stroke
				(width 0.1)
				(type default)
			)
			(layer "F.Fab")
		)
		(fp_poly
			(pts
				(xy -4.191 -3.258058) (xy -4.191 -2.242058) (xy -3.175 -2.750058)
			)
			(stroke
				(width 0)
				(type default)
			)
			(fill yes)
			(layer "F.Fab")
		)
		(pad "A1" smd circle
			(at -2.750058 -2.750058)
			(size 0.2286 0.2286)
			(layers "F.Cu" "F.Mask" "F.Paste")
			(net "Net_4313")
		)
		(pad "A2" smd circle
			(at -2.249932 -2.750058)
			(size 0.2286 0.2286)
			(layers "F.Cu" "F.Mask" "F.Paste")
			(net "Net_4312")
		)
		(pad "A3" smd circle
			(at -1.75006 -2.750058)
			(size 0.2286 0.2286)
			(layers "F.Cu" "F.Mask" "F.Paste")
			(net "Net_4311")
		)
		(pad "A4" smd circle
			(at -1.249934 -2.750058)
			(size 0.2286 0.2286)
			(layers "F.Cu" "F.Mask" "F.Paste")
			(net "CLK_100M_DB2000QL_GPU_REF2_DN")
		)
		(pad "A5" smd circle
			(at -0.750062 -2.750058)
			(size 0.2286 0.2286)
			(layers "F.Cu" "F.Mask" "F.Paste")
			(net "CLK_100M_DB2000QL_GPU_REF2_DP")
		)
		(pad "A6" smd circle
			(at -0.249936 -2.750058)
			(size 0.2286 0.2286)
			(layers "F.Cu" "F.Mask" "F.Paste")
			(net "CLK_100M_DB2000QL_GPU_REF1_DN")
		)
		(pad "A7" smd circle
			(at 0.249936 -2.750058)
			(size 0.2286 0.2286)
			(layers "F.Cu" "F.Mask" "F.Paste")
			(net "CLK_100M_DB2000QL_GPU_REF1_DP")
		)
		(pad "A8" smd circle
			(at 0.750062 -2.750058)
			(size 0.2286 0.2286)
			(layers "F.Cu" "F.Mask" "F.Paste")
			(net "CLK_100M_DB2000QL_GPU_REF0_DN")
		)
		(pad "A9" smd circle
			(at 1.249934 -2.750058)
			(size 0.2286 0.2286)
			(layers "F.Cu" "F.Mask" "F.Paste")
			(net "CLK_100M_DB2000QL_GPU_REF0_DP")
		)
		(pad "A10" smd circle
			(at 1.75006 -2.750058)
			(size 0.2286 0.2286)
			(layers "F.Cu" "F.Mask" "F.Paste")
			(net "CLK_100M_DB2000QL_NIC7_DN")
		)
		(pad "A11" smd circle
			(at 2.249932 -2.750058)
			(size 0.2286 0.2286)
			(layers "F.Cu" "F.Mask" "F.Paste")
			(net "CLK_100M_DB2000QL_NIC7_DP")
		)
		(pad "A12" smd circle
			(at 2.750058 -2.750058)
			(size 0.2286 0.2286)
			(layers "F.Cu" "F.Mask" "F.Paste")
			(net "CLK_100M_DB2000QL_NIC6_DN")
		)
		(pad "B1" smd circle
			(at -2.750058 -2.249932)
			(size 0.2286 0.2286)
			(layers "F.Cu" "F.Mask" "F.Paste")
			(net "Net_4314")
		)
		(pad "B2" smd circle
			(at -2.249932 -2.249932)
			(size 0.2286 0.2286)
			(layers "F.Cu" "F.Mask" "F.Paste")
			(net "P3V3_DB2000QL_VDD")
		)
		(pad "B3" smd circle
			(at -1.75006 -2.249932)
			(size 0.2286 0.2286)
			(layers "F.Cu" "F.Mask" "F.Paste")
			(net "Net_4321")
		)
		(pad "B4" smd circle
			(at -1.249934 -2.249932)
			(size 0.2286 0.2286)
			(layers "F.Cu" "F.Mask" "F.Paste")
			(net "FM_DB2000QL_SMB_SA0")
		)
		(pad "B5" smd circle
			(at -0.750062 -2.249932)
			(size 0.2286 0.2286)
			(layers "F.Cu" "F.Mask" "F.Paste")
			(net "Net_4331")
		)
		(pad "B6" smd circle
			(at -0.249936 -2.249932)
			(size 0.2286 0.2286)
			(layers "F.Cu" "F.Mask" "F.Paste")
			(net "P3V3_DB2000QL_VDDA")
		)
		(pad "B7" smd circle
			(at 0.249936 -2.249932)
			(size 0.2286 0.2286)
			(layers "F.Cu" "F.Mask" "F.Paste")
			(net "Net_4332")
		)
		(pad "B8" smd circle
			(at 0.750062 -2.249932)
			(size 0.2286 0.2286)
			(layers "F.Cu" "F.Mask" "F.Paste")
			(net "FM_DB2000QL_SMB_SA1")
		)
		(pad "B9" smd circle
			(at 1.249934 -2.249932)
			(size 0.2286 0.2286)
			(layers "F.Cu" "F.Mask" "F.Paste")
			(net "Net_4333")
		)
		(pad "B10" smd circle
			(at 1.75006 -2.249932)
			(size 0.2286 0.2286)
			(layers "F.Cu" "F.Mask" "F.Paste")
			(net "NIC7_CLK_EN_BUF_R_N")
		)
		(pad "B11" smd circle
			(at 2.249932 -2.249932)
			(size 0.2286 0.2286)
			(layers "F.Cu" "F.Mask" "F.Paste")
			(net "P3V3_DB2000QL_VDD")
		)
		(pad "B12" smd circle
			(at 2.750058 -2.249932)
			(size 0.2286 0.2286)
			(layers "F.Cu" "F.Mask" "F.Paste")
			(net "CLK_100M_DB2000QL_NIC6_DP")
		)
		(pad "C1" smd circle
			(at -2.750058 -1.75006)
			(size 0.2286 0.2286)
			(layers "F.Cu" "F.Mask" "F.Paste")
			(net "Net_4315")
		)
		(pad "C2" smd circle
			(at -2.249932 -1.75006)
			(size 0.2286 0.2286)
			(layers "F.Cu" "F.Mask" "F.Paste")
			(net "Net_4334")
		)
		(pad "C11" smd circle
			(at 2.249932 -1.75006)
			(size 0.2286 0.2286)
			(layers "F.Cu" "F.Mask" "F.Paste")
			(net "NIC6_CLK_EN_BUF_R_N")
		)
		(pad "C12" smd circle
			(at 2.750058 -1.75006)
			(size 0.2286 0.2286)
			(layers "F.Cu" "F.Mask" "F.Paste")
			(net "CLK_100M_DB2000QL_NIC5_DN")
		)
		(pad "D1" smd circle
			(at -2.750058 -1.249934)
			(size 0.2286 0.2286)
			(layers "F.Cu" "F.Mask" "F.Paste")
			(net "Net_4316")
		)
		(pad "D2" smd circle
			(at -2.249932 -1.249934)
			(size 0.2286 0.2286)
			(layers "F.Cu" "F.Mask" "F.Paste")
			(net "Net_4335")
		)
		(pad "D11" smd circle
			(at 2.249932 -1.249934)
			(size 0.2286 0.2286)
			(layers "F.Cu" "F.Mask" "F.Paste")
			(net "Net_4336")
		)
		(pad "D12" smd circle
			(at 2.750058 -1.249934)
			(size 0.2286 0.2286)
			(layers "F.Cu" "F.Mask" "F.Paste")
			(net "CLK_100M_DB2000QL_NIC5_DP")
		)
		(pad "E1" smd circle
			(at -2.750058 -0.750062)
			(size 0.2286 0.2286)
			(layers "F.Cu" "F.Mask" "F.Paste")
			(net "Net_4317")
		)
		(pad "E2" smd circle
			(at -2.249932 -0.750062)
			(size 0.2286 0.2286)
			(layers "F.Cu" "F.Mask" "F.Paste")
			(net "FM_DB2000QL_VSBEN")
		)
		(pad "E11" smd circle
			(at 2.249932 -0.750062)
			(size 0.2286 0.2286)
			(layers "F.Cu" "F.Mask" "F.Paste")
			(net "NIC5_CLK_EN_BUF_R_N")
		)
		(pad "E12" smd circle
			(at 2.750058 -0.750062)
			(size 0.2286 0.2286)
			(layers "F.Cu" "F.Mask" "F.Paste")
			(net "NIC4_CLK_EN_BUF_R_N")
		)
		(pad "F1" smd circle
			(at -2.750058 -0.249936)
			(size 0.2286 0.2286)
			(layers "F.Cu" "F.Mask" "F.Paste")
			(net "Net_4318")
		)
		(pad "F2" smd circle
			(at -2.249932 -0.249936)
			(size 0.2286 0.2286)
			(layers "F.Cu" "F.Mask" "F.Paste")
			(net "Net_4337")
		)
		(pad "F11" smd circle
			(at 2.249932 -0.249936)
			(size 0.2286 0.2286)
			(layers "F.Cu" "F.Mask" "F.Paste")
			(net "Net_4338")
		)
		(pad "F12" smd circle
			(at 2.750058 -0.249936)
			(size 0.2286 0.2286)
			(layers "F.Cu" "F.Mask" "F.Paste")
			(net "CLK_100M_DB2000QL_NIC4_DN")
		)
		(pad "G1" smd circle
			(at -2.750058 0.249936)
			(size 0.2286 0.2286)
			(layers "F.Cu" "F.Mask" "F.Paste")
			(net "CLK_100M_CK440Q_0_DB2000QL_R_DP")
		)
		(pad "G2" smd circle
			(at -2.249932 0.249936)
			(size 0.2286 0.2286)
			(layers "F.Cu" "F.Mask" "F.Paste")
			(net "Net_4322")
		)
		(pad "G11" smd circle
			(at 2.249932 0.249936)
			(size 0.2286 0.2286)
			(layers "F.Cu" "F.Mask" "F.Paste")
			(net "Net_4323")
		)
		(pad "G12" smd circle
			(at 2.750058 0.249936)
			(size 0.2286 0.2286)
			(layers "F.Cu" "F.Mask" "F.Paste")
			(net "CLK_100M_DB2000QL_NIC4_DP")
		)
		(pad "H1" smd circle
			(at -2.750058 0.750062)
			(size 0.2286 0.2286)
			(layers "F.Cu" "F.Mask" "F.Paste")
			(net "CLK_100M_CK440Q_0_DB2000QL_R_DN")
		)
		(pad "H2" smd circle
			(at -2.249932 0.750062)
			(size 0.2286 0.2286)
			(layers "F.Cu" "F.Mask" "F.Paste")
			(net "P3V3_DB2000QL_VDDR")
		)
		(pad "H11" smd circle
			(at 2.249932 0.750062)
			(size 0.2286 0.2286)
			(layers "F.Cu" "F.Mask" "F.Paste")
			(net "NIC3_CLK_EN_BUF_R_N")
		)
		(pad "H12" smd circle
			(at 2.750058 0.750062)
			(size 0.2286 0.2286)
			(layers "F.Cu" "F.Mask" "F.Paste")
			(net "CLK_100M_DB2000QL_NIC3_DN")
		)
		(pad "J1" smd circle
			(at -2.750058 1.249934)
			(size 0.2286 0.2286)
			(layers "F.Cu" "F.Mask" "F.Paste")
			(net "CLK_100M_DB2000QL_PEX0_S1_DP")
		)
		(pad "J2" smd circle
			(at -2.249932 1.249934)
			(size 0.2286 0.2286)
			(layers "F.Cu" "F.Mask" "F.Paste")
			(net "Net_4324")
		)
		(pad "J11" smd circle
			(at 2.249932 1.249934)
			(size 0.2286 0.2286)
			(layers "F.Cu" "F.Mask" "F.Paste")
			(net "Net_4325")
		)
		(pad "J12" smd circle
			(at 2.750058 1.249934)
			(size 0.2286 0.2286)
			(layers "F.Cu" "F.Mask" "F.Paste")
			(net "CLK_100M_DB2000QL_NIC3_DP")
		)
		(pad "K1" smd circle
			(at -2.750058 1.75006)
			(size 0.2286 0.2286)
			(layers "F.Cu" "F.Mask" "F.Paste")
			(net "CLK_100M_DB2000QL_PEX0_S1_DN")
		)
		(pad "K2" smd circle
			(at -2.249932 1.75006)
			(size 0.2286 0.2286)
			(layers "F.Cu" "F.Mask" "F.Paste")
			(net "Net_4326")
		)
		(pad "K11" smd circle
			(at 2.249932 1.75006)
			(size 0.2286 0.2286)
			(layers "F.Cu" "F.Mask" "F.Paste")
			(net "NIC2_CLK_EN_BUF_R_N")
		)
		(pad "K12" smd circle
			(at 2.750058 1.75006)
			(size 0.2286 0.2286)
			(layers "F.Cu" "F.Mask" "F.Paste")
			(net "CLK_100M_DB2000QL_NIC2_DN")
		)
		(pad "L1" smd circle
			(at -2.750058 2.249932)
			(size 0.2286 0.2286)
			(layers "F.Cu" "F.Mask" "F.Paste")
			(net "CLK_100M_DB2000QL_PEX1_S1_DP")
		)
		(pad "L2" smd circle
			(at -2.249932 2.249932)
			(size 0.2286 0.2286)
			(layers "F.Cu" "F.Mask" "F.Paste")
			(net "P3V3_DB2000QL_VDD")
		)
		(pad "L3" smd circle
			(at -1.75006 2.249932)
			(size 0.2286 0.2286)
			(layers "F.Cu" "F.Mask" "F.Paste")
			(net "Net_4329")
		)
		(pad "L4" smd circle
			(at -1.249934 2.249932)
			(size 0.2286 0.2286)
			(layers "F.Cu" "F.Mask" "F.Paste")
			(net "SMB_BMC_9QXL2001_SDA")
		)
		(pad "L5" smd circle
			(at -0.750062 2.249932)
			(size 0.2286 0.2286)
			(layers "F.Cu" "F.Mask" "F.Paste")
			(net "SMB_BMC_9QXL2001_SCL")
		)
		(pad "L6" smd circle
			(at -0.249936 2.249932)
			(size 0.2286 0.2286)
			(layers "F.Cu" "F.Mask" "F.Paste")
			(net "Net_4327")
		)
		(pad "L7" smd circle
			(at 0.249936 2.249932)
			(size 0.2286 0.2286)
			(layers "F.Cu" "F.Mask" "F.Paste")
			(net "Net_4328")
		)
		(pad "L8" smd circle
			(at 0.750062 2.249932)
			(size 0.2286 0.2286)
			(layers "F.Cu" "F.Mask" "F.Paste")
			(net "NIC0_CLK_EN_BUF_R_N")
		)
		(pad "L9" smd circle
			(at 1.249934 2.249932)
			(size 0.2286 0.2286)
			(layers "F.Cu" "F.Mask" "F.Paste")
			(net "Net_4330")
		)
		(pad "L10" smd circle
			(at 1.75006 2.249932)
			(size 0.2286 0.2286)
			(layers "F.Cu" "F.Mask" "F.Paste")
			(net "NIC1_CLK_EN_BUF_R_N")
		)
		(pad "L11" smd circle
			(at 2.249932 2.249932)
			(size 0.2286 0.2286)
			(layers "F.Cu" "F.Mask" "F.Paste")
			(net "P3V3_DB2000QL_VDD")
		)
		(pad "L12" smd circle
			(at 2.750058 2.249932)
			(size 0.2286 0.2286)
			(layers "F.Cu" "F.Mask" "F.Paste")
			(net "CLK_100M_DB2000QL_NIC2_DP")
		)
		(pad "M1" smd circle
			(at -2.750058 2.750058)
			(size 0.2286 0.2286)
			(layers "F.Cu" "F.Mask" "F.Paste")
			(net "CLK_100M_DB2000QL_PEX1_S1_DN")
		)
		(pad "M2" smd circle
			(at -2.249932 2.750058)
			(size 0.2286 0.2286)
			(layers "F.Cu" "F.Mask" "F.Paste")
			(net "CLK_100M_DB2000QL_PEX2_S1_DP")
		)
		(pad "M3" smd circle
			(at -1.75006 2.750058)
			(size 0.2286 0.2286)
			(layers "F.Cu" "F.Mask" "F.Paste")
			(net "CLK_100M_DB2000QL_PEX2_S1_DN")
		)
		(pad "M4" smd circle
			(at -1.249934 2.750058)
			(size 0.2286 0.2286)
			(layers "F.Cu" "F.Mask" "F.Paste")
			(net "CLK_100M_DB2000QL_PEX3_S1_DP")
		)
		(pad "M5" smd circle
			(at -0.750062 2.750058)
			(size 0.2286 0.2286)
			(layers "F.Cu" "F.Mask" "F.Paste")
			(net "CLK_100M_DB2000QL_PEX3_S1_DN")
		)
		(pad "M6" smd circle
			(at -0.249936 2.750058)
			(size 0.2286 0.2286)
			(layers "F.Cu" "F.Mask" "F.Paste")
			(net "FM_CLK_EN_R")
		)
		(pad "M7" smd circle
			(at 0.249936 2.750058)
			(size 0.2286 0.2286)
			(layers "F.Cu" "F.Mask" "F.Paste")
			(net "Net_4319")
		)
		(pad "M8" smd circle
			(at 0.750062 2.750058)
			(size 0.2286 0.2286)
			(layers "F.Cu" "F.Mask" "F.Paste")
			(net "Net_4320")
		)
		(pad "M9" smd circle
			(at 1.249934 2.750058)
			(size 0.2286 0.2286)
			(layers "F.Cu" "F.Mask" "F.Paste")
			(net "CLK_100M_DB2000QL_NIC0_DP")
		)
		(pad "M10" smd circle
			(at 1.75006 2.750058)
			(size 0.2286 0.2286)
			(layers "F.Cu" "F.Mask" "F.Paste")
			(net "CLK_100M_DB2000QL_NIC0_DN")
		)
		(pad "M11" smd circle
			(at 2.249932 2.750058)
			(size 0.2286 0.2286)
			(layers "F.Cu" "F.Mask" "F.Paste")
			(net "CLK_100M_DB2000QL_NIC1_DP")
		)
		(pad "M12" smd circle
			(at 2.750058 2.750058)
			(size 0.2286 0.2286)
			(layers "F.Cu" "F.Mask" "F.Paste")
			(net "CLK_100M_DB2000QL_NIC1_DN")
		)
		(pad "TH" smd circle
			(at 0 0)
			(size 0 0)
			(layers "F.Cu" "F.Mask" "F.Paste")
			(net "GND")
		)
		(zone
			(layer "F.Cu")
			(hatch none 0.5)
			(connect_pads
				(clearance 0)
			)
			(min_thickness 0.25)
			(keepout
				(tracks not_allowed)
				(vias allowed)
				(pads allowed)
				(copperpour not_allowed)
				(footprints allowed)
			)
			(placement
				(enabled no)
				(sheetname "")
			)
			(fill
				(thermal_gap 0.5)
				(thermal_bridge_width 0.5)
				(island_removal_mode 0)
			)
			(polygon
				(pts
					(xy 131.959096 -179.733194) (xy 134.803896 -179.733194) (xy 134.803896 -175.567594) (xy 130.638296 -175.567594)
					(xy 130.638296 -179.733194) (xy 131.933696 -179.733194) (xy 131.933696 -179.123594) (xy 131.654296 -179.123594)
					(xy 131.247896 -178.717194) (xy 131.247896 -176.177194) (xy 134.194296 -176.177194) (xy 134.194296 -179.123594)
					(xy 131.959096 -179.123594)
				)
			)
		)
	)
)
